(kicad_pcb
	(version 20260206)
	(generator "pcbnew")
	(generator_version "10.0")
	(general
		(thickness 1.6)
		(legacy_teardrops no)
	)
	(paper "A4")
	(title_block
		(title "fcb — Lightning_FCB_BRD.brd")
		(comment 1 "Lightning (Wiwynn / Facebook NVMe JBOF) / footprints 39-45 of 495")
	)
	(layers
		(0 "F.Cu" signal "TOP")
		(4 "In1.Cu" signal "L2GND")
		(6 "In2.Cu" signal "L3VCC")
		(2 "B.Cu" signal "BOTTOM")
		(9 "F.Adhes" user "F.Adhesive")
		(11 "B.Adhes" user "B.Adhesive")
		(13 "F.Paste" user "Package Geometry/Pastemask Top")
		(15 "B.Paste" user "Package Geometry/Pastemask Bottom")
		(5 "F.SilkS" user "Ref Des/Silkscreen Top")
		(7 "B.SilkS" user "Ref Des/Silkscreen Bottom")
		(1 "F.Mask" user "Board Geometry/Soldermask Top")
		(3 "B.Mask" user "Board Geometry/Soldermask Bottom")
		(17 "Dwgs.User" user "User.Drawings")
		(19 "Cmts.User" user "User.Comments")
		(21 "Eco1.User" user "User.Eco1")
		(23 "Eco2.User" user "User.Eco2")
		(25 "Edge.Cuts" user "Board Geometry/Outline")
		(27 "Margin" user)
		(31 "F.CrtYd" user "Package Geometry/Place Bound Top")
		(29 "B.CrtYd" user "Package Geometry/Place Bound Bottom")
		(35 "F.Fab" user "Ref Des/Assembly Top")
		(33 "B.Fab" user "Ref Des/Assembly Bottom")
	)
	(footprint ""
		(layer "F.Cu")
		(at 36.1188 -370.4336 90)
		(property "Reference" "PR8"
			(at 0 0 90)
			(layer "F.SilkS")
			(hide yes)
			(effects
				(font
					(size 1.27 1.27)
				)
			)
		)
		(property "Value" "11KR2F-L-GP"
			(at 0.064008 -3.993896 90)
			(unlocked yes)
			(layer "F.Fab")
			(hide yes)
			(effects
				(font
					(size 1.016 1.016)
					(thickness 0.1524)
				)
			)
		)
		(property "Device Type" "R402H16"
			(at 0.064008 -5.517896 90)
			(unlocked yes)
			(layer "F.Fab")
			(hide yes)
			(effects
				(font
					(size 1.016 1.016)
					(thickness 0.1524)
				)
			)
		)
		(duplicate_pad_numbers_are_jumpers no)
		(fp_line
			(start 0.508 -0.9398)
			(end -0.508 -0.9398)
			(stroke
				(width 0.1524)
				(type default)
			)
			(layer "F.SilkS")
		)
		(fp_line
			(start -0.508 -0.9398)
			(end -0.508 0.9398)
			(stroke
				(width 0.1524)
				(type default)
			)
			(layer "F.SilkS")
		)
		(fp_rect
			(start -0.508 0.9398)
			(end 0.508 -0.9398)
			(stroke
				(width 0)
				(type default)
			)
			(fill no)
			(layer "F.CrtYd")
		)
		(fp_rect
			(start -0.508 0.9398)
			(end 0.508 -0.9398)
			(stroke
				(width 0)
				(type default)
			)
			(fill no)
			(layer "F.Fab")
		)
		(pad "1" smd custom
			(at 0 -0.4445 90)
			(size 0.1397 0.1397)
			(layers "F.Cu" "F.Mask" "F.Paste")
			(net "ADM1276_FLB")
			(options
				(clearance outline)
				(anchor circle)
			)
			(primitives
				(gr_poly
					(pts
						(arc
							(start -0.1778 -0.2794)
							(mid -0.249642 -0.249642)
							(end -0.2794 -0.1778)
						)
						(arc
							(start -0.2794 0.1778)
							(mid -0.249642 0.249642)
							(end -0.1778 0.2794)
						)
						(arc
							(start 0.1778 0.2794)
							(mid 0.249642 0.249642)
							(end 0.2794 0.1778)
						)
						(arc
							(start 0.2794 -0.1778)
							(mid 0.249642 -0.249642)
							(end 0.1778 -0.2794)
						)
					)
					(width 0)
					(fill yes)
				)
			)
		)
		(pad "2" smd custom
			(at 0 0.4445 90)
			(size 0.1397 0.1397)
			(layers "F.Cu" "F.Mask" "F.Paste")
			(net "GND")
			(options
				(clearance outline)
				(anchor circle)
			)
			(primitives
				(gr_poly
					(pts
						(arc
							(start -0.1778 -0.2794)
							(mid -0.249642 -0.249642)
							(end -0.2794 -0.1778)
						)
						(arc
							(start -0.2794 0.1778)
							(mid -0.249642 0.249642)
							(end -0.1778 0.2794)
						)
						(arc
							(start 0.1778 0.2794)
							(mid 0.249642 0.249642)
							(end 0.2794 0.1778)
						)
						(arc
							(start 0.2794 -0.1778)
							(mid 0.249642 -0.249642)
							(end 0.1778 -0.2794)
						)
					)
					(width 0)
					(fill yes)
				)
			)
		)
	)
	(footprint ""
		(layer "F.Cu")
		(at 33.147 -376.428 90)
		(property "Reference" "PR14"
			(at 0 0 90)
			(layer "F.SilkS")
			(hide yes)
			(effects
				(font
					(size 1.27 1.27)
				)
			)
		)
		(property "Value" "0R2J-2-GP"
			(at 0.064008 -3.993896 90)
			(unlocked yes)
			(layer "F.Fab")
			(hide yes)
			(effects
				(font
					(size 1.016 1.016)
					(thickness 0.1524)
				)
			)
		)
		(property "Device Type" "R402H16"
			(at 0.064008 -5.517896 90)
			(unlocked yes)
			(layer "F.Fab")
			(hide yes)
			(effects
				(font
					(size 1.016 1.016)
					(thickness 0.1524)
				)
			)
		)
		(duplicate_pad_numbers_are_jumpers no)
		(fp_line
			(start 0.508 -0.9398)
			(end -0.508 -0.9398)
			(stroke
				(width 0.1524)
				(type default)
			)
			(layer "F.SilkS")
		)
		(fp_line
			(start -0.508 -0.9398)
			(end -0.508 0.9398)
			(stroke
				(width 0.1524)
				(type default)
			)
			(layer "F.SilkS")
		)
		(fp_rect
			(start -0.508 0.9398)
			(end 0.508 -0.9398)
			(stroke
				(width 0)
				(type default)
			)
			(fill no)
			(layer "F.CrtYd")
		)
		(fp_rect
			(start -0.508 0.9398)
			(end 0.508 -0.9398)
			(stroke
				(width 0)
				(type default)
			)
			(fill no)
			(layer "F.Fab")
		)
		(pad "1" smd custom
			(at 0 -0.4445 90)
			(size 0.1397 0.1397)
			(layers "F.Cu" "F.Mask" "F.Paste")
			(net "ADM1276_GATE")
			(options
				(clearance outline)
				(anchor circle)
			)
			(primitives
				(gr_poly
					(pts
						(arc
							(start -0.1778 -0.2794)
							(mid -0.249642 -0.249642)
							(end -0.2794 -0.1778)
						)
						(arc
							(start -0.2794 0.1778)
							(mid -0.249642 0.249642)
							(end -0.1778 0.2794)
						)
						(arc
							(start 0.1778 0.2794)
							(mid 0.249642 0.249642)
							(end 0.2794 0.1778)
						)
						(arc
							(start 0.2794 -0.1778)
							(mid 0.249642 -0.249642)
							(end 0.1778 -0.2794)
						)
					)
					(width 0)
					(fill yes)
				)
			)
		)
		(pad "2" smd custom
			(at 0 0.4445 90)
			(size 0.1397 0.1397)
			(layers "F.Cu" "F.Mask" "F.Paste")
			(net "ADM1276_GATE_RC")
			(options
				(clearance outline)
				(anchor circle)
			)
			(primitives
				(gr_poly
					(pts
						(arc
							(start -0.1778 -0.2794)
							(mid -0.249642 -0.249642)
							(end -0.2794 -0.1778)
						)
						(arc
							(start -0.2794 0.1778)
							(mid -0.249642 0.249642)
							(end -0.1778 0.2794)
						)
						(arc
							(start 0.1778 0.2794)
							(mid 0.249642 0.249642)
							(end 0.2794 0.1778)
						)
						(arc
							(start 0.2794 -0.1778)
							(mid 0.249642 -0.249642)
							(end 0.1778 -0.2794)
						)
					)
					(width 0)
					(fill yes)
				)
			)
		)
	)
	(footprint ""
		(layer "F.Cu")
		(at 29.9212 -247.4214)
		(property "Reference" "U5"
			(at 0 0 0)
			(layer "F.SilkS")
			(hide yes)
			(effects
				(font
					(size 1.27 1.27)
				)
			)
		)
		(property "Value" "24LC64T-I-GP"
			(at 0 -12.1412 0)
			(unlocked yes)
			(layer "F.Fab")
			(hide yes)
			(effects
				(font
					(size 1.016 1.016)
					(thickness 0.1524)
				)
			)
		)
		(property "Device Type" "SSOIC8-1H44"
			(at 0 -13.6652 0)
			(unlocked yes)
			(layer "F.Fab")
			(hide yes)
			(effects
				(font
					(size 1.016 1.016)
					(thickness 0.1524)
				)
			)
		)
		(duplicate_pad_numbers_are_jumpers no)
		(fp_line
			(start -1.778 -1.778)
			(end -1.778 2.667)
			(stroke
				(width 0.2032)
				(type default)
			)
			(layer "F.SilkS")
		)
		(fp_line
			(start -1.778 -1.778)
			(end 1.397 -1.778)
			(stroke
				(width 0.2032)
				(type default)
			)
			(layer "F.SilkS")
		)
		(fp_line
			(start -1.778 1.778)
			(end -1.778 3.81)
			(stroke
				(width 0.508)
				(type default)
			)
			(layer "F.SilkS")
		)
		(fp_line
			(start -1.143 0)
			(end -1.778 -0.635)
			(stroke
				(width 0.2032)
				(type default)
			)
			(layer "F.SilkS")
		)
		(fp_line
			(start -1.143 0)
			(end -1.778 0.635)
			(stroke
				(width 0.2032)
				(type default)
			)
			(layer "F.SilkS")
		)
		(fp_line
			(start 1.397 -1.778)
			(end 1.397 1.778)
			(stroke
				(width 0.2032)
				(type default)
			)
			(layer "F.SilkS")
		)
		(fp_line
			(start 1.397 1.778)
			(end -1.778 1.778)
			(stroke
				(width 0.2032)
				(type default)
			)
			(layer "F.SilkS")
		)
		(fp_poly
			(pts
				(xy -2.032 3.81) (xy 2.032 3.81) (xy 2.032 -3.81) (xy -2.032 -3.81)
			)
			(stroke
				(width 0)
				(type default)
			)
			(fill no)
			(layer "F.CrtYd")
		)
		(fp_poly
			(pts
				(xy -2.032 -3.81) (xy 2.032 -3.81) (xy 2.032 3.81) (xy -2.032 3.81)
			)
			(stroke
				(width 0)
				(type default)
			)
			(fill no)
			(layer "F.Fab")
		)
		(pad "1" smd rect
			(at -0.97536 2.8194)
			(size 0.3556 1.524)
			(layers "F.Cu" "F.Mask" "F.Paste")
			(net "FCB_EEPROM_A0")
		)
		(pad "2" smd rect
			(at -0.32512 2.8194)
			(size 0.3556 1.524)
			(layers "F.Cu" "F.Mask" "F.Paste")
			(net "FCB_EEPROM_A1")
		)
		(pad "3" smd rect
			(at 0.32512 2.8194)
			(size 0.3556 1.524)
			(layers "F.Cu" "F.Mask" "F.Paste")
			(net "FCB_EEPROM_A2")
		)
		(pad "4" smd rect
			(at 0.97536 2.8194)
			(size 0.3556 1.524)
			(layers "F.Cu" "F.Mask" "F.Paste")
			(net "GND")
		)
		(pad "5" smd rect
			(at 0.97536 -2.8194)
			(size 0.3556 1.524)
			(layers "F.Cu" "F.Mask" "F.Paste")
			(net "I2C_C_SDA_EEPROM")
		)
		(pad "6" smd rect
			(at 0.32512 -2.8194)
			(size 0.3556 1.524)
			(layers "F.Cu" "F.Mask" "F.Paste")
			(net "I2C_C_SCL_EEPROM")
		)
		(pad "7" smd rect
			(at -0.32512 -2.8194)
			(size 0.3556 1.524)
			(layers "F.Cu" "F.Mask" "F.Paste")
			(net "EEPROM_WP")
		)
		(pad "8" smd rect
			(at -0.97536 -2.8194)
			(size 0.3556 1.524)
			(layers "F.Cu" "F.Mask" "F.Paste")
			(net "P3V3")
		)
	)
	(footprint ""
		(layer "F.Cu")
		(at 33.71469 -150.730966 180)
		(property "Reference" "TP9"
			(at 0 0 180)
			(layer "F.SilkS")
			(hide yes)
			(effects
				(font
					(size 1.27 1.27)
				)
			)
		)
		(property "Value" "TPAD32-GP"
			(at 0 -3.166364 180)
			(unlocked yes)
			(layer "F.Fab")
			(hide yes)
			(effects
				(font
					(size 1.016 1.016)
					(thickness 0.1524)
				)
			)
		)
		(property "Device Type" "TPAD32"
			(at 0 -4.690618 180)
			(unlocked yes)
			(layer "F.Fab")
			(hide yes)
			(effects
				(font
					(size 1.016 1.016)
					(thickness 0.1524)
				)
			)
		)
		(duplicate_pad_numbers_are_jumpers no)
		(fp_poly
			(pts
				(arc
					(start 0.7112 0)
					(mid -0.7112 0)
					(end 0.7112 0)
				)
			)
			(stroke
				(width 0)
				(type default)
			)
			(fill no)
			(layer "F.CrtYd")
		)
		(fp_poly
			(pts
				(arc
					(start 0.7112 0)
					(mid -0.7112 0)
					(end 0.7112 0)
				)
			)
			(stroke
				(width 0)
				(type default)
			)
			(fill no)
			(layer "F.Fab")
		)
		(pad "1" smd circle
			(at 0 0 180)
			(size 0.8128 0.8128)
			(layers "F.Cu" "F.Mask" "F.Paste")
			(net "NCT7904_VSEN10")
		)
	)
	(footprint ""
		(layer "F.Cu")
		(at 21.844 -202.7936 -90)
		(property "Reference" "TC15"
			(at 0 0 270)
			(layer "F.SilkS")
			(hide yes)
			(effects
				(font
					(size 1.27 1.27)
				)
			)
		)
		(property "Value" "ST15U25VDM-1-GP"
			(at 0 -9.6012 270)
			(unlocked yes)
			(layer "F.Fab")
			(hide yes)
			(effects
				(font
					(size 1.016 1.016)
					(thickness 0.1524)
				)
			)
		)
		(property "Device Type" "CT7343H79"
			(at 0 -11.1252 270)
			(unlocked yes)
			(layer "F.Fab")
			(hide yes)
			(effects
				(font
					(size 1.016 1.016)
					(thickness 0.1524)
				)
			)
		)
		(duplicate_pad_numbers_are_jumpers no)
		(fp_line
			(start -2.286 4.8768)
			(end -2.286 2.032)
			(stroke
				(width 0.1524)
				(type default)
			)
			(layer "F.SilkS")
		)
		(fp_line
			(start 2.286 4.8768)
			(end -2.286 4.8768)
			(stroke
				(width 0.1524)
				(type default)
			)
			(layer "F.SilkS")
		)
		(fp_line
			(start 2.286 2.032)
			(end 2.286 4.8768)
			(stroke
				(width 0.1524)
				(type default)
			)
			(layer "F.SilkS")
		)
		(fp_line
			(start 2.286 -2.032)
			(end 2.286 -4.8768)
			(stroke
				(width 0.1524)
				(type default)
			)
			(layer "F.SilkS")
		)
		(fp_line
			(start 2.1082 -4.699)
			(end -2.1082 -4.699)
			(stroke
				(width 0.508)
				(type default)
			)
			(layer "F.SilkS")
		)
		(fp_line
			(start -2.286 -4.8768)
			(end -2.286 -2.032)
			(stroke
				(width 0.1524)
				(type default)
			)
			(layer "F.SilkS")
		)
		(fp_line
			(start 2.286 -4.8768)
			(end -2.286 -4.8768)
			(stroke
				(width 0.1524)
				(type default)
			)
			(layer "F.SilkS")
		)
		(fp_rect
			(start -2.1463 3.6449)
			(end 2.1463 -3.6449)
			(stroke
				(width 0)
				(type default)
			)
			(fill no)
			(layer "F.CrtYd")
		)
		(fp_poly
			(pts
				(xy -2.54 4.953) (xy -2.54 4.2926) (xy -3.81 4.2926) (xy -3.81 -4.2926) (xy -2.54 -4.2926) (xy -2.54 -4.953)
				(xy 2.54 -4.953) (xy 2.54 -4.2926) (xy 3.81 -4.2926) (xy 3.81 -1.6256) (xy 2.1463 -1.6256) (xy 2.1463 -3.6449)
				(xy -2.1463 -3.6449) (xy -2.1463 3.6449) (xy 2.1463 3.6449) (xy 2.1463 -1.6129) (xy 3.81 -1.6129)
				(xy 3.81 4.2926) (xy 2.54 4.2926) (xy 2.54 4.953)
			)
			(stroke
				(width 0)
				(type default)
			)
			(fill no)
			(layer "F.CrtYd")
		)
		(fp_rect
			(start -2.54 4.953)
			(end 2.54 -4.953)
			(stroke
				(width 0)
				(type default)
			)
			(fill no)
			(layer "F.Fab")
		)
		(fp_rect
			(start -3.81 4.2926)
			(end -2.54 -4.2926)
			(stroke
				(width 0)
				(type default)
			)
			(fill no)
			(layer "F.Fab")
		)
		(fp_rect
			(start 2.54 4.2926)
			(end 3.81 -4.2926)
			(stroke
				(width 0)
				(type default)
			)
			(fill no)
			(layer "F.Fab")
		)
		(pad "1" smd rect
			(at 0 -3.1496 270)
			(size 2.413 2.286)
			(layers "F.Cu" "F.Mask" "F.Paste")
			(net "P12V")
		)
		(pad "2" smd rect
			(at 0 3.1496 270)
			(size 2.413 2.286)
			(layers "F.Cu" "F.Mask" "F.Paste")
			(net "GND")
		)
		(zone
			(layer "F.Cu")
			(hatch none 0.5)
			(connect_pads
				(clearance 0)
			)
			(min_thickness 0.25)
			(keepout
				(tracks allowed)
				(vias not_allowed)
				(pads allowed)
				(copperpour not_allowed)
				(footprints allowed)
			)
			(placement
				(enabled no)
				(sheetname "")
			)
			(fill
				(thermal_gap 0.5)
				(thermal_bridge_width 0.5)
				(island_removal_mode 0)
			)
			(polygon
				(pts
					(xy 17.2466 -204.3049) (xy 17.2466 -201.2823) (xy 20.1422 -201.2823) (xy 20.4724 -201.2823) (xy 20.4724 -204.3049)
					(xy 20.1422 -204.3049)
				)
			)
		)
		(zone
			(layer "F.Cu")
			(hatch none 0.5)
			(connect_pads
				(clearance 0)
			)
			(min_thickness 0.25)
			(keepout
				(tracks allowed)
				(vias not_allowed)
				(pads allowed)
				(copperpour not_allowed)
				(footprints allowed)
			)
			(placement
				(enabled no)
				(sheetname "")
			)
			(fill
				(thermal_gap 0.5)
				(thermal_bridge_width 0.5)
				(island_removal_mode 0)
			)
			(polygon
				(pts
					(xy 23.5331 -201.2823) (xy 26.4414 -201.2823) (xy 26.4414 -204.3049) (xy 23.5458 -204.3049) (xy 23.2156 -204.3049)
					(xy 23.2156 -201.2823)
				)
			)
		)
	)
	(footprint ""
		(layer "F.Cu")
		(at 32.749998 -451.820026)
		(property "Reference" "CN8"
			(at 0 0 0)
			(layer "F.SilkS")
			(hide yes)
			(effects
				(font
					(size 1.27 1.27)
				)
			)
		)
		(property "Value" "JWT-CON3-S11-GP"
			(at 5.715 1.1684 0)
			(unlocked yes)
			(layer "F.Fab")
			(hide yes)
			(effects
				(font
					(size 1.016 1.016)
					(thickness 0.1524)
				)
			)
		)
		(property "Device Type" "A2541WV0-1QX3PA-6T"
			(at 5.715 -0.3556 0)
			(unlocked yes)
			(layer "F.Fab")
			(hide yes)
			(effects
				(font
					(size 1.016 1.016)
					(thickness 0.1524)
				)
			)
		)
		(duplicate_pad_numbers_are_jumpers no)
		(fp_line
			(start -4.190746 -1.651)
			(end -2.920746 -1.651)
			(stroke
				(width 0.4064)
				(type default)
			)
			(layer "F.SilkS")
		)
		(fp_line
			(start -4.190746 -0.381)
			(end -4.190746 -1.651)
			(stroke
				(width 0.4064)
				(type default)
			)
			(layer "F.SilkS")
		)
		(fp_line
			(start -4.064 -1.524)
			(end -4.064 1.524)
			(stroke
				(width 0.1524)
				(type default)
			)
			(layer "F.SilkS")
		)
		(fp_line
			(start -4.064 1.524)
			(end 4.064 1.524)
			(stroke
				(width 0.1524)
				(type default)
			)
			(layer "F.SilkS")
		)
		(fp_line
			(start 4.064 -1.524)
			(end -4.064 -1.524)
			(stroke
				(width 0.1524)
				(type default)
			)
			(layer "F.SilkS")
		)
		(fp_line
			(start 4.064 1.524)
			(end 4.064 -1.524)
			(stroke
				(width 0.1524)
				(type default)
			)
			(layer "F.SilkS")
		)
		(fp_circle
			(center -2.54 0)
			(end -1.4732 0)
			(stroke
				(width 0.3048)
				(type default)
			)
			(fill no)
			(layer "F.SilkS")
		)
		(fp_circle
			(center 0 0)
			(end 1.0668 0)
			(stroke
				(width 0.3048)
				(type default)
			)
			(fill no)
			(layer "F.SilkS")
		)
		(fp_circle
			(center 2.54 0)
			(end 3.6068 0)
			(stroke
				(width 0.3048)
				(type default)
			)
			(fill no)
			(layer "F.SilkS")
		)
		(fp_rect
			(start -3.81 1.27)
			(end 3.81 -1.27)
			(stroke
				(width 0)
				(type default)
			)
			(fill no)
			(layer "F.CrtYd")
		)
		(fp_poly
			(pts
				(xy -4.318 1.778) (xy -4.318 -1.778) (xy 4.318 -1.778) (xy 4.318 -1.27) (xy -3.81 -1.27) (xy -3.81 1.27)
				(xy 3.81 1.27) (xy 3.81 -1.2573) (xy 4.318 -1.2573) (xy 4.318 1.778)
			)
			(stroke
				(width 0)
				(type default)
			)
			(fill no)
			(layer "F.CrtYd")
		)
		(fp_rect
			(start -4.318 1.778)
			(end 4.318 -1.778)
			(stroke
				(width 0)
				(type default)
			)
			(fill no)
			(layer "F.Fab")
		)
		(pad "1" thru_hole circle
			(at -2.54 0)
			(size 1.4224 1.4224)
			(drill 1.016)
			(layers "*.Cu" "*.Mask")
			(remove_unused_layers no)
			(net "Net_4")
			(clearance 0.1524)
			(thermal_gap 0.1524)
		)
		(pad "2" thru_hole circle
			(at 0 0)
			(size 1.4224 1.4224)
			(drill 1.016)
			(layers "*.Cu" "*.Mask")
			(remove_unused_layers no)
			(net "Net_3")
			(clearance 0.1524)
			(thermal_gap 0.1524)
		)
		(pad "3" thru_hole circle
			(at 2.54 0)
			(size 1.4224 1.4224)
			(drill 1.016)
			(layers "*.Cu" "*.Mask")
			(remove_unused_layers no)
			(net "Net_2")
			(clearance 0.1524)
			(thermal_gap 0.1524)
		)
	)
	(footprint ""
		(layer "F.Cu")
		(at 26.035 -267.6398 90)
		(property "Reference" "C39"
			(at 0 0 90)
			(layer "F.SilkS")
			(hide yes)
			(effects
				(font
					(size 1.27 1.27)
				)
			)
		)
		(property "Value" "SCD1U50V3KX-GP"
			(at 0 -2.8194 90)
			(unlocked yes)
			(layer "F.Fab")
			(hide yes)
			(effects
				(font
					(size 1.016 1.016)
					(thickness 0.1524)
				)
			)
		)
		(property "Device Type" "C603H36"
			(at 0 -4.3434 90)
			(unlocked yes)
			(layer "F.Fab")
			(hide yes)
			(effects
				(font
					(size 1.016 1.016)
					(thickness 0.1524)
				)
			)
		)
		(duplicate_pad_numbers_are_jumpers no)
		(fp_line
			(start 0.508 0)
			(end -0.508 0)
			(stroke
				(width 0.2032)
				(type default)
			)
			(layer "F.SilkS")
		)
		(fp_rect
			(start -0.5842 1.3335)
			(end 0.5842 -1.3335)
			(stroke
				(width 0)
				(type default)
			)
			(fill no)
			(layer "F.CrtYd")
		)
		(fp_rect
			(start -0.5842 1.3335)
			(end 0.5842 -1.3335)
			(stroke
				(width 0)
				(type default)
			)
			(fill no)
			(layer "F.Fab")
		)
		(pad "1" smd custom
			(at 0 -0.762 90)
			(size 0.2159 0.2159)
			(layers "F.Cu" "F.Mask" "F.Paste")
			(net "P12V")
			(options
				(clearance outline)
				(anchor circle)
			)
			(primitives
				(gr_poly
					(pts
						(arc
							(start -0.3302 -0.4318)
							(mid -0.402042 -0.402042)
							(end -0.4318 -0.3302)
						)
						(arc
							(start -0.4318 0.3302)
							(mid -0.402042 0.402042)
							(end -0.3302 0.4318)
						)
						(arc
							(start 0.3302 0.4318)
							(mid 0.402042 0.402042)
							(end 0.4318 0.3302)
						)
						(arc
							(start 0.4318 -0.3302)
							(mid 0.402042 -0.402042)
							(end 0.3302 -0.4318)
						)
					)
					(width 0)
					(fill yes)
				)
			)
		)
		(pad "2" smd custom
			(at 0 0.762 90)
			(size 0.2159 0.2159)
			(layers "F.Cu" "F.Mask" "F.Paste")
			(net "GND")
			(options
				(clearance outline)
				(anchor circle)
			)
			(primitives
				(gr_poly
					(pts
						(arc
							(start -0.3302 -0.4318)
							(mid -0.402042 -0.402042)
							(end -0.4318 -0.3302)
						)
						(arc
							(start -0.4318 0.3302)
							(mid -0.402042 0.402042)
							(end -0.3302 0.4318)
						)
						(arc
							(start 0.3302 0.4318)
							(mid 0.402042 0.402042)
							(end 0.4318 0.3302)
						)
						(arc
							(start 0.4318 -0.3302)
							(mid 0.402042 -0.402042)
							(end 0.3302 -0.4318)
						)
					)
					(width 0)
					(fill yes)
				)
			)
		)
	)
)
